FILE_TYPE = MULTI_PHYS_TABLE;
PART 'PXM1310B'
{============================================================================================================================================================================}
:PACK_TYPE | MATERIAL | PART_NUMBER     = EnvComp | PART_NUMBER  | JEDEC_TYPE     | DESCRIPTION                                 | CLASS | COMPONENT_TYPE | HEIGHT     | LPID  | SPEED_URL | Status |RPL| AML | Bus_Unit | Days ;
{============================================================================================================================================================================}
'QFN'      | 'IC'     | 'H89186-001'(!) = ''      | 'H89186-001' | 'QFN40_20_4MB' | 'IC,LIN,QFN,PXM1310B,CONTROLR'              | 'IC'  | 'LCC'          | '0.035 IN' | '3556' | 'http://speed.intel.com:8081/speed/module/pdm/item/pdm_item_detail_direct.asp?item_cde=H89186-001&item_rev=01&url_param=unused' | '' | '' | '' | '' | '' 
'QFN'      | 'EMPTY'  | 'H89186-001'(!) = ''      | 'H89186-001' | 'QFN40_20_4MB' | 'IC,LIN,QFN,PXM1310B,CONTROLR'              | 'IO'  | 'LCC'          | '0.035 IN' | '3556' | 'http://speed.intel.com:8081/speed/module/pdm/item/pdm_item_detail_direct.asp?item_cde=H89186-001&item_rev=01&url_param=unused' | '' | '' | '' | '' | '' 
END_PART
END.
